(kicad_pcb
	(version 20260206)
	(generator "pcbnew")
	(generator_version "10.0")
	(general
		(thickness 1.6)
		(legacy_teardrops no)
	)
	(paper "A4")
	(title_block
		(title "panther-plus-userver — 13130-1b_20150205.brd")
		(comment 1 "Honey Badger (Wiwynn) / footprint 894 of 1509 (DIMM1), pads 205-210 of 210")
	)
	(layers
		(0 "F.Cu" signal "TOP")
		(4 "In1.Cu" signal "L2")
		(6 "In2.Cu" signal "L3")
		(8 "In3.Cu" signal "L4")
		(10 "In4.Cu" signal "L5")
		(12 "In5.Cu" signal "L6")
		(14 "In6.Cu" signal "L7")
		(16 "In7.Cu" signal "L8")
		(18 "In8.Cu" signal "L9")
		(20 "In9.Cu" signal "L10")
		(22 "In10.Cu" signal "L11")
		(2 "B.Cu" signal "BOTTOM")
		(9 "F.Adhes" user "F.Adhesive")
		(11 "B.Adhes" user "B.Adhesive")
		(13 "F.Paste" user "Package Geometry/Pastemask Top")
		(15 "B.Paste" user "Package Geometry/Pastemask Bottom")
		(5 "F.SilkS" user "Ref Des/Silkscreen Top")
		(7 "B.SilkS" user "Ref Des/Silkscreen Bottom")
		(1 "F.Mask" user "Board Geometry/Soldermask Top")
		(3 "B.Mask" user "Board Geometry/Soldermask Bottom")
		(17 "Dwgs.User" user "User.Drawings")
		(19 "Cmts.User" user "User.Comments")
		(21 "Eco1.User" user "User.Eco1")
		(23 "Eco2.User" user "User.Eco2")
		(25 "Edge.Cuts" user "Board Geometry/Outline")
		(27 "Margin" user)
		(31 "F.CrtYd" user "Package Geometry/Place Bound Top")
		(29 "B.CrtYd" user "Package Geometry/Place Bound Bottom")
		(35 "F.Fab" user "Ref Des/Assembly Top")
		(33 "B.Fab" user "Ref Des/Assembly Bottom")
	)
	(footprint ""
		(layer "B.Cu")
		(at 158.500064 -66.699892 180)
		(property "Reference" "DIMM1"
			(at 0 0 0)
			(layer "B.SilkS")
			(hide yes)
			(effects
				(font
					(size 1.27 1.27)
				)
				(justify mirror)
			)
		)
		(property "Value" "DDR3-204P-142-COLAY-1-GP-U"
			(at 41.312338 -16.676878 180)
			(unlocked yes)
			(layer "B.Fab")
			(hide yes)
			(effects
				(font
					(size 1.016 1.016)
					(thickness 0.1524)
				)
				(justify mirror)
			)
		)
		(property "Device Type" "AS0A626-J8R6-7H-COLAY-1"
			(at 41.312338 -18.200878 180)
			(unlocked yes)
			(layer "B.Fab")
			(hide yes)
			(effects
				(font
					(size 1.016 1.016)
					(thickness 0.1524)
				)
				(justify mirror)
			)
		)
		(duplicate_pad_numbers_are_jumpers no)
		(pad "203" smd custom
			(at 31.34995 -4.100068)
			(size 0.1143 0.1143)
			(layers "B.Cu" "B.Mask" "B.Paste")
			(net "PV_VTT_DDR_A")
			(options
				(clearance outline)
				(anchor circle)
			)
			(primitives
				(gr_poly
					(pts
						(xy 0 -0.9017) (xy -0.03175 -0.89916) (xy -0.0635 -0.889) (xy -0.09144 -0.87376) (xy -0.11684 -0.85344)
						(xy -0.13716 -0.82804) (xy -0.1524 -0.8001) (xy -0.16256 -0.76835) (xy -0.1651 -0.7366) (xy -0.1651 -0.19685)
						(xy -0.17272 -0.18923) (xy -0.17907 -0.18034) (xy -0.18669 -0.17145) (xy -0.19177 -0.16256) (xy -0.19812 -0.15367)
						(xy -0.20828 -0.13335) (xy -0.21971 -0.10287) (xy -0.22225 -0.09271) (xy -0.22479 -0.08128) (xy -0.22606 -0.07112)
						(xy -0.2286 -0.05969) (xy -0.2286 -0.01651) (xy -0.22606 -0.00508) (xy -0.22479 0.00508) (xy -0.22225 0.01651)
						(xy -0.21971 0.02667) (xy -0.20828 0.05715) (xy -0.19812 0.07747) (xy -0.19177 0.08636) (xy -0.18669 0.09525)
						(xy -0.17907 0.10414) (xy -0.17272 0.11303) (xy -0.1651 0.12065) (xy -0.1651 0.7366) (xy -0.16256 0.76835)
						(xy -0.1524 0.8001) (xy -0.13716 0.82804) (xy -0.11684 0.85344) (xy -0.09144 0.87376) (xy -0.0635 0.889)
						(xy -0.03175 0.89916) (xy 0 0.9017) (xy 0.03175 0.89916) (xy 0.0635 0.889) (xy 0.09144 0.87376)
						(xy 0.11684 0.85344) (xy 0.13716 0.82804) (xy 0.1524 0.8001) (xy 0.16256 0.76835) (xy 0.1651 0.7366)
						(xy 0.1651 0.11938) (xy 0.17272 0.11176) (xy 0.19812 0.0762) (xy 0.2032 0.06604) (xy 0.20701 0.05715)
						(xy 0.21209 0.04699) (xy 0.2159 0.03683) (xy 0.21844 0.02667) (xy 0.22225 0.01524) (xy 0.22352 0.00508)
						(xy 0.22606 -0.00508) (xy 0.22733 -0.01651) (xy 0.22733 -0.02667) (xy 0.2286 -0.0381) (xy 0.22733 -0.04953)
						(xy 0.22733 -0.05969) (xy 0.22606 -0.07112) (xy 0.22352 -0.08128) (xy 0.22225 -0.09144) (xy 0.21844 -0.10287)
						(xy 0.2159 -0.11303) (xy 0.21209 -0.12319) (xy 0.20701 -0.13335) (xy 0.2032 -0.14224) (xy 0.19812 -0.1524)
						(xy 0.17272 -0.18796) (xy 0.1651 -0.19558) (xy 0.1651 -0.7366) (xy 0.16256 -0.76835) (xy 0.1524 -0.8001)
						(xy 0.13716 -0.82804) (xy 0.11684 -0.85344) (xy 0.09144 -0.87376) (xy 0.0635 -0.889) (xy 0.03175 -0.89916)
					)
					(width 0)
					(fill yes)
				)
			)
		)
		(pad "204" smd custom
			(at 31.649924 4.100068)
			(size 0.1143 0.1143)
			(layers "B.Cu" "B.Mask" "B.Paste")
			(net "PV_VTT_DDR_A")
			(options
				(clearance outline)
				(anchor circle)
			)
			(primitives
				(gr_poly
					(pts
						(xy 0 -0.9017) (xy -0.03175 -0.89916) (xy -0.0635 -0.889) (xy -0.09144 -0.87376) (xy -0.11684 -0.85344)
						(xy -0.13716 -0.82804) (xy -0.1524 -0.8001) (xy -0.16256 -0.76835) (xy -0.1651 -0.7366) (xy -0.1651 -0.11938)
						(xy -0.17272 -0.11176) (xy -0.19812 -0.0762) (xy -0.2032 -0.06604) (xy -0.20701 -0.05715) (xy -0.21209 -0.04699)
						(xy -0.2159 -0.03683) (xy -0.21844 -0.02667) (xy -0.22225 -0.01524) (xy -0.22352 -0.00508) (xy -0.22606 0.00508)
						(xy -0.22733 0.01651) (xy -0.22733 0.02667) (xy -0.2286 0.0381) (xy -0.22733 0.04953) (xy -0.22733 0.05969)
						(xy -0.22606 0.07112) (xy -0.22352 0.08128) (xy -0.22225 0.09144) (xy -0.21844 0.10287) (xy -0.2159 0.11303)
						(xy -0.21209 0.12319) (xy -0.20701 0.13335) (xy -0.2032 0.14224) (xy -0.19812 0.1524) (xy -0.17272 0.18796)
						(xy -0.1651 0.19558) (xy -0.1651 0.7366) (xy -0.16256 0.76835) (xy -0.1524 0.8001) (xy -0.13716 0.82804)
						(xy -0.11684 0.85344) (xy -0.09144 0.87376) (xy -0.0635 0.889) (xy -0.03175 0.89916) (xy 0 0.9017)
						(xy 0.03175 0.89916) (xy 0.0635 0.889) (xy 0.09144 0.87376) (xy 0.11684 0.85344) (xy 0.13716 0.82804)
						(xy 0.1524 0.8001) (xy 0.16256 0.76835) (xy 0.1651 0.7366) (xy 0.1651 0.19685) (xy 0.17272 0.18923)
						(xy 0.17907 0.18034) (xy 0.18669 0.17145) (xy 0.19177 0.16256) (xy 0.19812 0.15367) (xy 0.20828 0.13335)
						(xy 0.21971 0.10287) (xy 0.22225 0.09271) (xy 0.22479 0.08128) (xy 0.22606 0.07112) (xy 0.2286 0.05969)
						(xy 0.2286 0.01651) (xy 0.22606 0.00508) (xy 0.22479 -0.00508) (xy 0.22225 -0.01651) (xy 0.21971 -0.02667)
						(xy 0.20828 -0.05715) (xy 0.19812 -0.07747) (xy 0.19177 -0.08636) (xy 0.18669 -0.09525) (xy 0.17907 -0.10414)
						(xy 0.17272 -0.11303) (xy 0.1651 -0.12065) (xy 0.1651 -0.7366) (xy 0.16256 -0.76835) (xy 0.1524 -0.8001)
						(xy 0.13716 -0.82804) (xy 0.11684 -0.85344) (xy 0.09144 -0.87376) (xy 0.0635 -0.889) (xy 0.03175 -0.89916)
					)
					(width 0)
					(fill yes)
				)
			)
		)
		(pad "205" smd rect
			(at 37.450014 -11.999976)
			(size 4.4958 4.5974)
			(layers "B.Cu" "B.Mask" "B.Paste")
			(net "GND")
		)
		(pad "206" smd rect
			(at 32.800036 -11.999976)
			(size 3.5052 4.5974)
			(layers "B.Cu" "B.Mask" "B.Paste")
			(net "GND")
		)
		(pad "207" smd rect
			(at -32.800036 -11.999976)
			(size 3.5052 4.5974)
			(layers "B.Cu" "B.Mask" "B.Paste")
			(net "GND")
		)
		(pad "208" smd rect
			(at -37.450014 -11.999976)
			(size 4.4958 4.5974)
			(layers "B.Cu" "B.Mask" "B.Paste")
			(net "GND")
		)
	)
)
